(kicad_pcb
	(version 20260206)
	(generator "pcbnew")
	(generator_version "10.0")
	(general
		(thickness 1.6)
		(legacy_teardrops no)
	)
	(paper "A4")
	(title_block
		(title "01162023_DA0F0TEBIF0_F0T_Expander_BD_F_brd_V02_OCP.brd")
		(comment 1 "Grand Teton / footprints 2320-2325 of 9728")
	)
	(layers
		(0 "F.Cu" signal "TOP")
		(4 "In1.Cu" signal "GND")
		(6 "In2.Cu" signal "VCC")
		(8 "In3.Cu" signal "VCC1")
		(10 "In4.Cu" signal "GND1")
		(12 "In5.Cu" signal "IN1")
		(14 "In6.Cu" signal "GND2")
		(16 "In7.Cu" signal "IN2")
		(18 "In8.Cu" signal "GND3")
		(20 "In9.Cu" signal "IN3")
		(22 "In10.Cu" signal "GND4")
		(24 "In11.Cu" signal "IN4")
		(26 "In12.Cu" signal "GND5")
		(28 "In13.Cu" signal "IN5")
		(30 "In14.Cu" signal "GND6")
		(32 "In15.Cu" signal "IN6")
		(34 "In16.Cu" signal "GND7")
		(2 "B.Cu" signal "BOTTOM")
		(9 "F.Adhes" user "F.Adhesive")
		(11 "B.Adhes" user "B.Adhesive")
		(13 "F.Paste" user "Package Geometry/Pastemask Top")
		(15 "B.Paste" user "Package Geometry/Pastemask Bottom")
		(5 "F.SilkS" user "Ref Des/Silkscreen Top")
		(7 "B.SilkS" user "Ref Des/Silkscreen Bottom")
		(1 "F.Mask" user "Board Geometry/Soldermask Top")
		(3 "B.Mask" user "Board Geometry/Soldermask Bottom")
		(17 "Dwgs.User" user "User.Drawings")
		(19 "Cmts.User" user "User.Comments")
		(21 "Eco1.User" user "User.Eco1")
		(23 "Eco2.User" user "User.Eco2")
		(25 "Edge.Cuts" user "Board Geometry/Outline")
		(27 "Margin" user)
		(31 "F.CrtYd" user "Package Geometry/Place Bound Top")
		(29 "B.CrtYd" user "Package Geometry/Place Bound Bottom")
		(35 "F.Fab" user "Ref Des/Assembly Top")
		(33 "B.Fab" user "Ref Des/Assembly Bottom")
	)
	(footprint ""
		(layer "F.Cu")
		(at 286.385 -84.836 180)
		(property "Reference" "R490"
			(at 0 0 180)
			(layer "F.SilkS")
			(hide yes)
			(effects
				(font
					(size 1.27 1.27)
				)
			)
		)
		(property "Value" ""
			(at 0 0 180)
			(layer "F.Fab")
			(effects
				(font
					(size 1.27 1.27)
				)
			)
		)
		(duplicate_pad_numbers_are_jumpers no)
		(fp_line
			(start 0.7874 0.4064)
			(end -0.7874 0.4064)
			(stroke
				(width 0.1524)
				(type default)
			)
			(layer "F.SilkS")
		)
		(fp_line
			(start 0.7874 -0.4064)
			(end 0.7874 0.4064)
			(stroke
				(width 0.1524)
				(type default)
			)
			(layer "F.SilkS")
		)
		(fp_line
			(start -0.7874 0.4064)
			(end -0.7874 -0.4064)
			(stroke
				(width 0.1524)
				(type default)
			)
			(layer "F.SilkS")
		)
		(fp_line
			(start -0.7874 -0.4064)
			(end 0.7874 -0.4064)
			(stroke
				(width 0.1524)
				(type default)
			)
			(layer "F.SilkS")
		)
		(fp_line
			(start 0.67945 0.3048)
			(end 0.120396 0.3048)
			(stroke
				(width 0.1)
				(type default)
			)
			(layer "F.Fab")
		)
		(fp_line
			(start 0.67945 -0.3048)
			(end 0.67945 0.3048)
			(stroke
				(width 0.1)
				(type default)
			)
			(layer "F.Fab")
		)
		(fp_line
			(start 0.12065 -0.2794)
			(end 0.12065 -0.3048)
			(stroke
				(width 0.1)
				(type default)
			)
			(layer "F.Fab")
		)
		(fp_line
			(start 0.12065 -0.3048)
			(end 0.67945 -0.3048)
			(stroke
				(width 0.1)
				(type default)
			)
			(layer "F.Fab")
		)
		(fp_line
			(start 0.120396 0.3048)
			(end 0.120396 0.2794)
			(stroke
				(width 0.1)
				(type default)
			)
			(layer "F.Fab")
		)
		(fp_line
			(start 0.120396 0.2794)
			(end -0.12065 0.2794)
			(stroke
				(width 0.1)
				(type default)
			)
			(layer "F.Fab")
		)
		(fp_line
			(start -0.12065 0.3048)
			(end -0.67945 0.3048)
			(stroke
				(width 0.1)
				(type default)
			)
			(layer "F.Fab")
		)
		(fp_line
			(start -0.12065 0.2794)
			(end -0.12065 0.3048)
			(stroke
				(width 0.1)
				(type default)
			)
			(layer "F.Fab")
		)
		(fp_line
			(start -0.12065 -0.2794)
			(end 0.12065 -0.2794)
			(stroke
				(width 0.1)
				(type default)
			)
			(layer "F.Fab")
		)
		(fp_line
			(start -0.12065 -0.305054)
			(end -0.12065 -0.2794)
			(stroke
				(width 0.1)
				(type default)
			)
			(layer "F.Fab")
		)
		(fp_line
			(start -0.67945 0.3048)
			(end -0.67945 -0.305054)
			(stroke
				(width 0.1)
				(type default)
			)
			(layer "F.Fab")
		)
		(fp_line
			(start -0.67945 -0.305054)
			(end -0.12065 -0.305054)
			(stroke
				(width 0.1)
				(type default)
			)
			(layer "F.Fab")
		)
		(pad "1" smd circle
			(at -0.40005 0 180)
			(size 0 0)
			(layers "F.Cu" "F.Mask" "F.Paste")
			(net "BB_FRU_A1")
		)
		(pad "2" smd circle
			(at 0.40005 0 180)
			(size 0 0)
			(layers "F.Cu" "F.Mask" "F.Paste")
			(net "GND")
		)
	)
	(footprint ""
		(layer "F.Cu")
		(at 348.742 -205.232 90)
		(property "Reference" "R4152"
			(at 0 0 90)
			(layer "F.SilkS")
			(hide yes)
			(effects
				(font
					(size 1.27 1.27)
				)
			)
		)
		(property "Value" ""
			(at 0 0 90)
			(layer "F.Fab")
			(effects
				(font
					(size 1.27 1.27)
				)
			)
		)
		(duplicate_pad_numbers_are_jumpers no)
		(fp_line
			(start 0.7874 -0.4064)
			(end 0.7874 0.4064)
			(stroke
				(width 0.1524)
				(type default)
			)
			(layer "F.SilkS")
		)
		(fp_line
			(start -0.7874 -0.4064)
			(end 0.7874 -0.4064)
			(stroke
				(width 0.1524)
				(type default)
			)
			(layer "F.SilkS")
		)
		(fp_line
			(start 0.7874 0.4064)
			(end -0.7874 0.4064)
			(stroke
				(width 0.1524)
				(type default)
			)
			(layer "F.SilkS")
		)
		(fp_line
			(start -0.7874 0.4064)
			(end -0.7874 -0.4064)
			(stroke
				(width 0.1524)
				(type default)
			)
			(layer "F.SilkS")
		)
		(fp_line
			(start -0.12065 -0.305054)
			(end -0.12065 -0.2794)
			(stroke
				(width 0.1)
				(type default)
			)
			(layer "F.Fab")
		)
		(fp_line
			(start -0.67945 -0.305054)
			(end -0.12065 -0.305054)
			(stroke
				(width 0.1)
				(type default)
			)
			(layer "F.Fab")
		)
		(fp_line
			(start 0.67945 -0.3048)
			(end 0.67945 0.3048)
			(stroke
				(width 0.1)
				(type default)
			)
			(layer "F.Fab")
		)
		(fp_line
			(start 0.12065 -0.3048)
			(end 0.67945 -0.3048)
			(stroke
				(width 0.1)
				(type default)
			)
			(layer "F.Fab")
		)
		(fp_line
			(start 0.12065 -0.2794)
			(end 0.12065 -0.3048)
			(stroke
				(width 0.1)
				(type default)
			)
			(layer "F.Fab")
		)
		(fp_line
			(start -0.12065 -0.2794)
			(end 0.12065 -0.2794)
			(stroke
				(width 0.1)
				(type default)
			)
			(layer "F.Fab")
		)
		(fp_line
			(start 0.120396 0.2794)
			(end -0.12065 0.2794)
			(stroke
				(width 0.1)
				(type default)
			)
			(layer "F.Fab")
		)
		(fp_line
			(start -0.12065 0.2794)
			(end -0.12065 0.3048)
			(stroke
				(width 0.1)
				(type default)
			)
			(layer "F.Fab")
		)
		(fp_line
			(start 0.67945 0.3048)
			(end 0.120396 0.3048)
			(stroke
				(width 0.1)
				(type default)
			)
			(layer "F.Fab")
		)
		(fp_line
			(start 0.120396 0.3048)
			(end 0.120396 0.2794)
			(stroke
				(width 0.1)
				(type default)
			)
			(layer "F.Fab")
		)
		(fp_line
			(start -0.12065 0.3048)
			(end -0.67945 0.3048)
			(stroke
				(width 0.1)
				(type default)
			)
			(layer "F.Fab")
		)
		(fp_line
			(start -0.67945 0.3048)
			(end -0.67945 -0.305054)
			(stroke
				(width 0.1)
				(type default)
			)
			(layer "F.Fab")
		)
		(pad "1" smd circle
			(at -0.40005 0 90)
			(size 0 0)
			(layers "F.Cu" "F.Mask" "F.Paste")
			(net "PRSNT_SSD5_FPGA_R_N")
		)
		(pad "2" smd circle
			(at 0.40005 0 90)
			(size 0 0)
			(layers "F.Cu" "F.Mask" "F.Paste")
			(net "PRSNT_SSD5_FPGA_N")
		)
	)
	(footprint ""
		(layer "F.Cu")
		(at 225.775774 -280.10104 180)
		(property "Reference" "C826"
			(at 0 0 180)
			(layer "F.SilkS")
			(hide yes)
			(effects
				(font
					(size 1.27 1.27)
				)
			)
		)
		(property "Value" ""
			(at 0 0 180)
			(layer "F.Fab")
			(effects
				(font
					(size 1.27 1.27)
				)
			)
		)
		(duplicate_pad_numbers_are_jumpers no)
		(fp_line
			(start 0.7874 0.4064)
			(end -0.7874 0.4064)
			(stroke
				(width 0.1524)
				(type default)
			)
			(layer "F.SilkS")
		)
		(fp_line
			(start 0.7874 -0.4064)
			(end 0.7874 0.4064)
			(stroke
				(width 0.1524)
				(type default)
			)
			(layer "F.SilkS")
		)
		(fp_line
			(start -0.7874 0.4064)
			(end -0.7874 -0.4064)
			(stroke
				(width 0.1524)
				(type default)
			)
			(layer "F.SilkS")
		)
		(fp_line
			(start -0.7874 -0.4064)
			(end 0.7874 -0.4064)
			(stroke
				(width 0.1524)
				(type default)
			)
			(layer "F.SilkS")
		)
		(fp_line
			(start 0.67945 0.3048)
			(end 0.120396 0.3048)
			(stroke
				(width 0.1)
				(type default)
			)
			(layer "F.Fab")
		)
		(fp_line
			(start 0.67945 -0.3048)
			(end 0.67945 0.3048)
			(stroke
				(width 0.1)
				(type default)
			)
			(layer "F.Fab")
		)
		(fp_line
			(start 0.12065 -0.2794)
			(end 0.12065 -0.3048)
			(stroke
				(width 0.1)
				(type default)
			)
			(layer "F.Fab")
		)
		(fp_line
			(start 0.12065 -0.3048)
			(end 0.67945 -0.3048)
			(stroke
				(width 0.1)
				(type default)
			)
			(layer "F.Fab")
		)
		(fp_line
			(start 0.120396 0.3048)
			(end 0.120396 0.2794)
			(stroke
				(width 0.1)
				(type default)
			)
			(layer "F.Fab")
		)
		(fp_line
			(start 0.120396 0.2794)
			(end -0.12065 0.2794)
			(stroke
				(width 0.1)
				(type default)
			)
			(layer "F.Fab")
		)
		(fp_line
			(start -0.12065 0.3048)
			(end -0.67945 0.3048)
			(stroke
				(width 0.1)
				(type default)
			)
			(layer "F.Fab")
		)
		(fp_line
			(start -0.12065 0.2794)
			(end -0.12065 0.3048)
			(stroke
				(width 0.1)
				(type default)
			)
			(layer "F.Fab")
		)
		(fp_line
			(start -0.12065 -0.2794)
			(end 0.12065 -0.2794)
			(stroke
				(width 0.1)
				(type default)
			)
			(layer "F.Fab")
		)
		(fp_line
			(start -0.12065 -0.305054)
			(end -0.12065 -0.2794)
			(stroke
				(width 0.1)
				(type default)
			)
			(layer "F.Fab")
		)
		(fp_line
			(start -0.67945 0.3048)
			(end -0.67945 -0.305054)
			(stroke
				(width 0.1)
				(type default)
			)
			(layer "F.Fab")
		)
		(fp_line
			(start -0.67945 -0.305054)
			(end -0.12065 -0.305054)
			(stroke
				(width 0.1)
				(type default)
			)
			(layer "F.Fab")
		)
		(pad "1" smd circle
			(at -0.40005 0 180)
			(size 0 0)
			(layers "F.Cu" "F.Mask" "F.Paste")
			(net "P3V3_AUX")
		)
		(pad "2" smd circle
			(at 0.40005 0 180)
			(size 0 0)
			(layers "F.Cu" "F.Mask" "F.Paste")
			(net "GND")
		)
	)
	(footprint ""
		(layer "F.Cu")
		(at 261.07517 -64.102234 180)
		(property "Reference" "PR7080"
			(at 0 0 180)
			(layer "F.SilkS")
			(hide yes)
			(effects
				(font
					(size 1.27 1.27)
				)
			)
		)
		(property "Value" ""
			(at 0 0 180)
			(layer "F.Fab")
			(effects
				(font
					(size 1.27 1.27)
				)
			)
		)
		(duplicate_pad_numbers_are_jumpers no)
		(fp_line
			(start 0.7874 0.4064)
			(end -0.7874 0.4064)
			(stroke
				(width 0.1524)
				(type default)
			)
			(layer "F.SilkS")
		)
		(fp_line
			(start 0.7874 -0.4064)
			(end 0.7874 0.4064)
			(stroke
				(width 0.1524)
				(type default)
			)
			(layer "F.SilkS")
		)
		(fp_line
			(start -0.7874 0.4064)
			(end -0.7874 -0.4064)
			(stroke
				(width 0.1524)
				(type default)
			)
			(layer "F.SilkS")
		)
		(fp_line
			(start -0.7874 -0.4064)
			(end 0.7874 -0.4064)
			(stroke
				(width 0.1524)
				(type default)
			)
			(layer "F.SilkS")
		)
		(fp_line
			(start 0.67945 0.3048)
			(end 0.120396 0.3048)
			(stroke
				(width 0.1)
				(type default)
			)
			(layer "F.Fab")
		)
		(fp_line
			(start 0.67945 -0.3048)
			(end 0.67945 0.3048)
			(stroke
				(width 0.1)
				(type default)
			)
			(layer "F.Fab")
		)
		(fp_line
			(start 0.12065 -0.2794)
			(end 0.12065 -0.3048)
			(stroke
				(width 0.1)
				(type default)
			)
			(layer "F.Fab")
		)
		(fp_line
			(start 0.12065 -0.3048)
			(end 0.67945 -0.3048)
			(stroke
				(width 0.1)
				(type default)
			)
			(layer "F.Fab")
		)
		(fp_line
			(start 0.120396 0.3048)
			(end 0.120396 0.2794)
			(stroke
				(width 0.1)
				(type default)
			)
			(layer "F.Fab")
		)
		(fp_line
			(start 0.120396 0.2794)
			(end -0.12065 0.2794)
			(stroke
				(width 0.1)
				(type default)
			)
			(layer "F.Fab")
		)
		(fp_line
			(start -0.12065 0.3048)
			(end -0.67945 0.3048)
			(stroke
				(width 0.1)
				(type default)
			)
			(layer "F.Fab")
		)
		(fp_line
			(start -0.12065 0.2794)
			(end -0.12065 0.3048)
			(stroke
				(width 0.1)
				(type default)
			)
			(layer "F.Fab")
		)
		(fp_line
			(start -0.12065 -0.2794)
			(end 0.12065 -0.2794)
			(stroke
				(width 0.1)
				(type default)
			)
			(layer "F.Fab")
		)
		(fp_line
			(start -0.12065 -0.305054)
			(end -0.12065 -0.2794)
			(stroke
				(width 0.1)
				(type default)
			)
			(layer "F.Fab")
		)
		(fp_line
			(start -0.67945 0.3048)
			(end -0.67945 -0.305054)
			(stroke
				(width 0.1)
				(type default)
			)
			(layer "F.Fab")
		)
		(fp_line
			(start -0.67945 -0.305054)
			(end -0.12065 -0.305054)
			(stroke
				(width 0.1)
				(type default)
			)
			(layer "F.Fab")
		)
		(pad "1" smd circle
			(at -0.40005 0 180)
			(size 0 0)
			(layers "F.Cu" "F.Mask" "F.Paste")
			(net "P12V_SSD9_PG_G1")
		)
		(pad "2" smd circle
			(at 0.40005 0 180)
			(size 0 0)
			(layers "F.Cu" "F.Mask" "F.Paste")
			(net "GND")
		)
	)
	(footprint ""
		(layer "F.Cu")
		(at 336.509868 -280.44902 -90)
		(property "Reference" "PC146"
			(at 0 0 270)
			(layer "F.SilkS")
			(hide yes)
			(effects
				(font
					(size 1.27 1.27)
				)
			)
		)
		(property "Value" ""
			(at 0 0 270)
			(layer "F.Fab")
			(effects
				(font
					(size 1.27 1.27)
				)
			)
		)
		(duplicate_pad_numbers_are_jumpers no)
		(fp_line
			(start -0.7874 0.4064)
			(end -0.7874 -0.4064)
			(stroke
				(width 0.1524)
				(type default)
			)
			(layer "F.SilkS")
		)
		(fp_line
			(start 0.7874 0.4064)
			(end -0.7874 0.4064)
			(stroke
				(width 0.1524)
				(type default)
			)
			(layer "F.SilkS")
		)
		(fp_line
			(start -0.7874 -0.4064)
			(end 0.7874 -0.4064)
			(stroke
				(width 0.1524)
				(type default)
			)
			(layer "F.SilkS")
		)
		(fp_line
			(start 0.7874 -0.4064)
			(end 0.7874 0.4064)
			(stroke
				(width 0.1524)
				(type default)
			)
			(layer "F.SilkS")
		)
		(fp_line
			(start -0.67945 0.3048)
			(end -0.67945 -0.305054)
			(stroke
				(width 0.1)
				(type default)
			)
			(layer "F.Fab")
		)
		(fp_line
			(start -0.12065 0.3048)
			(end -0.67945 0.3048)
			(stroke
				(width 0.1)
				(type default)
			)
			(layer "F.Fab")
		)
		(fp_line
			(start 0.120396 0.3048)
			(end 0.120396 0.2794)
			(stroke
				(width 0.1)
				(type default)
			)
			(layer "F.Fab")
		)
		(fp_line
			(start 0.67945 0.3048)
			(end 0.120396 0.3048)
			(stroke
				(width 0.1)
				(type default)
			)
			(layer "F.Fab")
		)
		(fp_line
			(start -0.12065 0.2794)
			(end -0.12065 0.3048)
			(stroke
				(width 0.1)
				(type default)
			)
			(layer "F.Fab")
		)
		(fp_line
			(start 0.120396 0.2794)
			(end -0.12065 0.2794)
			(stroke
				(width 0.1)
				(type default)
			)
			(layer "F.Fab")
		)
		(fp_line
			(start -0.12065 -0.2794)
			(end 0.12065 -0.2794)
			(stroke
				(width 0.1)
				(type default)
			)
			(layer "F.Fab")
		)
		(fp_line
			(start 0.12065 -0.2794)
			(end 0.12065 -0.3048)
			(stroke
				(width 0.1)
				(type default)
			)
			(layer "F.Fab")
		)
		(fp_line
			(start 0.12065 -0.3048)
			(end 0.67945 -0.3048)
			(stroke
				(width 0.1)
				(type default)
			)
			(layer "F.Fab")
		)
		(fp_line
			(start 0.67945 -0.3048)
			(end 0.67945 0.3048)
			(stroke
				(width 0.1)
				(type default)
			)
			(layer "F.Fab")
		)
		(fp_line
			(start -0.67945 -0.305054)
			(end -0.12065 -0.305054)
			(stroke
				(width 0.1)
				(type default)
			)
			(layer "F.Fab")
		)
		(fp_line
			(start -0.12065 -0.305054)
			(end -0.12065 -0.2794)
			(stroke
				(width 0.1)
				(type default)
			)
			(layer "F.Fab")
		)
		(pad "1" smd circle
			(at -0.40005 0 270)
			(size 0 0)
			(layers "F.Cu" "F.Mask" "F.Paste")
			(net "SW_P0V8_PEX2_PHASE1")
		)
		(pad "2" smd circle
			(at 0.40005 0 270)
			(size 0 0)
			(layers "F.Cu" "F.Mask" "F.Paste")
			(net "SW_P0V8_PEX2_BOOT1_R")
		)
	)
	(footprint ""
		(layer "F.Cu")
		(at 375.686828 -307.803296 -135)
		(property "Reference" "R1398"
			(at 0 0 225)
			(layer "F.SilkS")
			(hide yes)
			(effects
				(font
					(size 1.27 1.27)
				)
			)
		)
		(property "Value" ""
			(at 0 0 225)
			(layer "F.Fab")
			(effects
				(font
					(size 1.27 1.27)
				)
			)
		)
		(duplicate_pad_numbers_are_jumpers no)
		(fp_line
			(start 0.787389 0.406267)
			(end -0.787389 0.406267)
			(stroke
				(width 0.1524)
				(type default)
			)
			(layer "F.SilkS")
		)
		(fp_line
			(start 0.787389 -0.406267)
			(end 0.787389 0.406267)
			(stroke
				(width 0.1524)
				(type default)
			)
			(layer "F.SilkS")
		)
		(fp_line
			(start -0.787389 0.406267)
			(end -0.787389 -0.406267)
			(stroke
				(width 0.1524)
				(type default)
			)
			(layer "F.SilkS")
		)
		(fp_line
			(start -0.787389 -0.406267)
			(end 0.787389 -0.406267)
			(stroke
				(width 0.1524)
				(type default)
			)
			(layer "F.SilkS")
		)
		(fp_line
			(start 0.679446 0.30479)
			(end 0.120515 0.30479)
			(stroke
				(width 0.1)
				(type default)
			)
			(layer "F.Fab")
		)
		(fp_line
			(start 0.120515 0.30479)
			(end 0.120335 0.279466)
			(stroke
				(width 0.1)
				(type default)
			)
			(layer "F.Fab")
		)
		(fp_line
			(start 0.120335 0.279466)
			(end -0.120695 0.279466)
			(stroke
				(width 0.1)
				(type default)
			)
			(layer "F.Fab")
		)
		(fp_line
			(start 0.679446 -0.30479)
			(end 0.679446 0.30479)
			(stroke
				(width 0.1)
				(type default)
			)
			(layer "F.Fab")
		)
		(fp_line
			(start -0.120515 0.30479)
			(end -0.679446 0.30479)
			(stroke
				(width 0.1)
				(type default)
			)
			(layer "F.Fab")
		)
		(fp_line
			(start -0.120695 0.279466)
			(end -0.120515 0.30479)
			(stroke
				(width 0.1)
				(type default)
			)
			(layer "F.Fab")
		)
		(fp_line
			(start 0.120695 -0.279466)
			(end 0.120515 -0.30479)
			(stroke
				(width 0.1)
				(type default)
			)
			(layer "F.Fab")
		)
		(fp_line
			(start 0.120515 -0.30479)
			(end 0.679446 -0.30479)
			(stroke
				(width 0.1)
				(type default)
			)
			(layer "F.Fab")
		)
		(fp_line
			(start -0.679446 0.30479)
			(end -0.679446 -0.305149)
			(stroke
				(width 0.1)
				(type default)
			)
			(layer "F.Fab")
		)
		(fp_line
			(start -0.120695 -0.279466)
			(end 0.120695 -0.279466)
			(stroke
				(width 0.1)
				(type default)
			)
			(layer "F.Fab")
		)
		(fp_line
			(start -0.120695 -0.304969)
			(end -0.120695 -0.279466)
			(stroke
				(width 0.1)
				(type default)
			)
			(layer "F.Fab")
		)
		(fp_line
			(start -0.679446 -0.305149)
			(end -0.120695 -0.304969)
			(stroke
				(width 0.1)
				(type default)
			)
			(layer "F.Fab")
		)
		(pad "1" smd circle
			(at -0.40005 0 225)
			(size 0 0)
			(layers "F.Cu" "F.Mask" "F.Paste")
			(net "PEX3_DBG_SEL0")
		)
		(pad "2" smd circle
			(at 0.40005 0 225)
			(size 0 0)
			(layers "F.Cu" "F.Mask" "F.Paste")
			(net "P1V8_PEX")
		)
	)
)
